# Stackup_F0T_Management_Board_12L_1p6mm_IT-170GRA1_RG311_Rev0p2_20220715 的複本.xls — Stackup (pcb-stackup)
| STACKUP |  |  |  | Target Z (ohms) - MicroStrip |  |  |  |  | 50 | Breakout | 85 |  | 100 |  | Breakout |  |
|  |  |  |  | Target Z (ohms) - StripLine |  |  |  |  | 50 |  | 85 |  | 100 |  |  |  |
|  |  |  |  | Z tolerance |  |  |  |  | 0.1 |  | 0.1 |  | 0.1 |  |  |  |
|  |  |  |  | Z Type |  |  |  |  | Single | Single | Differential |  | Differential |  | Differential |  |
| Layer# | Material | Description |  | Copper Weight (oz) | Thickness (mil) | Tolerance (mil) | Glass Fabric | Er | Width | Width | Width | Space | Width | Space | Width | Space |
|  |  |  | Soldermask |  | 0.6 |  |  | 3.8 |  |  |  |  |  |  |  |  |
| 1 |  |  | TOP | 0.5+plating | 1.95 |  |  |  | 4.6 | 3.29 | 5.6 | 8.9 | 4 | 11 | 3.39 | 4 |
|  | IT-170GRA1 |  | PP |  | 2.7 | ±0.709 | 1080x1 | 3.65 |  |  |  |  |  |  |  |  |
| 2 |  |  | GND | 0.5 (RG311) | 0.65 |  |  |  |  |  |  |  |  |  |  |  |
|  | IT-170GRA1 |  | CORE |  | 3 | ±0.709 | 1086x1 | 3.65 |  |  |  |  |  |  |  |  |
| 3 |  |  | IN1 | 0.5 (RG311) | 0.65 |  |  |  | 3.3 | 3.29 | 4.5 | 8.7 | 3.4 | 13.2 | 3.39 | 4 |
|  | IT-170GRA1 |  | PP |  | 4.5 | ±0.709 | 2116x1 | 3.67 |  |  |  |  |  |  |  |  |
| 4 |  |  | GND1 | 0.5 (RG311) | 0.65 |  |  |  |  |  |  |  |  |  |  |  |
|  | IT-170GRA1 |  | CORE |  | 3 | ±0.709 | 1086x1 | 3.65 |  |  |  |  |  |  |  |  |
| 5 |  |  | IN2 | 0.5 (RG311) | 0.65 |  |  |  | 4.2 | 3.29 | 5.4 | 8.6 | 4 | 9.6 | 3.39 | 4 |
|  | IT-170GRA1 |  | PP |  | 9.35 | ±1.5 | 2116x2 | 3.71 |  |  |  |  |  |  |  |  |
| 6 |  |  | VCC | 1 (RG311) | 1.3 |  |  |  |  |  |  |  |  |  |  |  |
|  | IT-170GRA1 |  | CORE |  | 5 | ±0.984 | 2116x1 | 3.67 |  |  |  |  |  |  |  |  |
| 7 |  |  | VCC1 | 1 (RG311) | 1.3 |  |  |  |  |  |  |  |  |  |  |  |
|  | IT-170GRA1 |  | PP |  | 9.35 | ±1.5 | 2116x2 | 3.71 |  |  |  |  |  |  |  |  |
| 8 |  |  | IN3 | 0.5 (RG311) | 0.65 |  |  |  | 4.2 | 3.29 | 5.4 | 8.6 | 4 | 9.6 | 3.39 | 4 |
|  | IT-170GRA1 |  | CORE |  | 3 | ±0.709 | 1086x1 | 3.65 |  |  |  |  |  |  |  |  |
| 9 |  |  | GND2 | 0.5 (RG311) | 0.65 |  |  |  |  |  |  |  |  |  |  |  |
|  | IT-170GRA1 |  | PP |  | 4.5 | ±0.709 | 2116x1 | 3.67 |  |  |  |  |  |  |  |  |
| 10 |  |  | IN4 | 0.5 (RG311) | 0.65 |  |  |  | 3.3 | 3.29 | 4.5 | 8.7 | 3.4 | 13.2 | 3.39 | 4 |
|  | IT-170GRA1 |  | CORE |  | 3 | ±0.709 | 1086x1 | 3.65 |  |  |  |  |  |  |  |  |
| 11 |  |  | GND3 | 0.5 (RG311) | 0.65 |  |  |  |  |  |  |  |  |  |  |  |
|  | IT-170GRA1 |  | PP |  | 2.7 | ±0.709 | 1080x1 | 3.65 |  |  |  |  |  |  |  |  |
| 12 |  |  | BOTTOM | 0.5+plating | 1.95 |  |  |  | 4.6 | 3.29 | 5.6 | 8.9 | 4 | 11 | 3.39 | 4 |
|  |  |  | Soldermask |  | 0.6 |  |  | 3.8 |  |  |  |  |  |  |  |  |
|  |  |  |  | Total | 63 | ±10% |  |  |  |  |  |  |  |  |  |  |
